# S9S_MB_2U (Grand Teton) — schematic netlist excerpt (pin names and nets, part order shuffled) for the footprints in the layout excerpt that follows; sources: Cadence DE-HDL packaged netlist, KiCad conversion of 03242023_DA0F0TMBIJ0_F0T_Motherboard_J_brd_V01_OCP.brd

PC259_P0_5  Q_CAP  22UF 16V 20% X6S  pkg C0805  page 269 : A = SW_P12V_PVCCIN_CPU0_FLT ; B = GND
R280  Q_RES  240 1% EMPTY  pkg 0402LF  page 119 : A = PVNN_TERM_CPU0 ; B = PU_CPU0_SOCKET_ID1
R2479  Q_RES  33.2 1% CHIP  pkg 0402LF  page 235 : A = SMB_PEHPCPU1_LVC3_SCL_R0 ; B = SMB_PEHPCPU1_LVC3_SCL

(kicad_pcb
	(version 20260206)
	(generator "pcbnew")
	(generator_version "10.0")
	(general
		(thickness 1.6)
		(legacy_teardrops no)
	)
	(paper "A4")
	(title_block
		(title "03242023_DA0F0TMBIJ0_F0T_Motherboard_J_brd_V01_OCP.brd")
		(comment 1 "Grand Teton / footprints 4399-4401 of 6105")
	)
	(layers
		(0 "F.Cu" signal "TOP")
		(4 "In1.Cu" signal "GND")
		(6 "In2.Cu" signal "IN1")
		(8 "In3.Cu" signal "GND1")
		(10 "In4.Cu" signal "IN2")
		(12 "In5.Cu" signal "GND2")
		(14 "In6.Cu" signal "IN3")
		(16 "In7.Cu" signal "GND3")
		(18 "In8.Cu" signal "VCC")
		(20 "In9.Cu" signal "VCC1")
		(22 "In10.Cu" signal "GND4")
		(24 "In11.Cu" signal "IN4")
		(26 "In12.Cu" signal "GND5")
		(28 "In13.Cu" signal "IN5")
		(30 "In14.Cu" signal "GND6")
		(32 "In15.Cu" signal "IN6")
		(34 "In16.Cu" signal "GND7")
		(2 "B.Cu" signal "BOTTOM")
		(9 "F.Adhes" user "F.Adhesive")
		(11 "B.Adhes" user "B.Adhesive")
		(13 "F.Paste" user "Package Geometry/Pastemask Top")
		(15 "B.Paste" user "Package Geometry/Pastemask Bottom")
		(5 "F.SilkS" user "Ref Des/Silkscreen Top")
		(7 "B.SilkS" user "Ref Des/Silkscreen Bottom")
		(1 "F.Mask" user "Board Geometry/Soldermask Top")
		(3 "B.Mask" user "Board Geometry/Soldermask Bottom")
		(17 "Dwgs.User" user "User.Drawings")
		(19 "Cmts.User" user "User.Comments")
		(21 "Eco1.User" user "User.Eco1")
		(23 "Eco2.User" user "User.Eco2")
		(25 "Edge.Cuts" user "Board Geometry/Outline")
		(27 "Margin" user)
		(31 "F.CrtYd" user "Package Geometry/Place Bound Top")
		(29 "B.CrtYd" user "Package Geometry/Place Bound Bottom")
		(35 "F.Fab" user "Ref Des/Assembly Top")
		(33 "B.Fab" user "Ref Des/Assembly Bottom")
	)
	(footprint ""
		(layer "B.Cu")
		(at 378.7013 -337.145884 90)
		(property "Reference" "PC259_P0_5"
			(at 0 0 90)
			(layer "B.SilkS")
			(hide yes)
			(effects
				(font
					(size 1.27 1.27)
				)
				(justify mirror)
			)
		)
		(property "Value" ""
			(at 0 0 90)
			(layer "B.Fab")
			(effects
				(font
					(size 1.27 1.27)
				)
				(justify mirror)
			)
		)
		(duplicate_pad_numbers_are_jumpers no)
		(fp_line
			(start 1.524 -0.762)
			(end -1.524 -0.762)
			(stroke
				(width 0.1524)
				(type default)
			)
			(layer "B.SilkS")
		)
		(fp_line
			(start -1.524 -0.762)
			(end -1.524 0.762)
			(stroke
				(width 0.1524)
				(type default)
			)
			(layer "B.SilkS")
		)
		(fp_line
			(start 1.524 0.762)
			(end 1.524 -0.762)
			(stroke
				(width 0.1524)
				(type default)
			)
			(layer "B.SilkS")
		)
		(fp_line
			(start -1.524 0.762)
			(end 1.524 0.762)
			(stroke
				(width 0.1524)
				(type default)
			)
			(layer "B.SilkS")
		)
		(fp_line
			(start 1.1049 -0.724916)
			(end 1.1049 0.724916)
			(stroke
				(width 0.1)
				(type default)
			)
			(layer "B.Fab")
		)
		(fp_line
			(start -1.1049 -0.724916)
			(end 1.1049 -0.724916)
			(stroke
				(width 0.1)
				(type default)
			)
			(layer "B.Fab")
		)
		(fp_line
			(start 1.1049 0.724916)
			(end -1.1049 0.724916)
			(stroke
				(width 0.1)
				(type default)
			)
			(layer "B.Fab")
		)
		(fp_line
			(start -1.1049 0.724916)
			(end -1.1049 -0.724916)
			(stroke
				(width 0.1)
				(type default)
			)
			(layer "B.Fab")
		)
		(pad "1" smd rect
			(at 0.889 0 90)
			(size 1.016 1.27)
			(layers "B.Cu" "B.Mask" "B.Paste")
			(net "SW_P12V_PVCCIN_CPU0_FLT")
		)
		(pad "2" smd rect
			(at -0.889 0 90)
			(size 1.016 1.27)
			(layers "B.Cu" "B.Mask" "B.Paste")
			(net "GND")
		)
	)
	(footprint ""
		(layer "B.Cu")
		(at 409.140152 -193.08953 -90)
		(property "Reference" "R280"
			(at 0 0 90)
			(layer "B.SilkS")
			(hide yes)
			(effects
				(font
					(size 1.27 1.27)
				)
				(justify mirror)
			)
		)
		(property "Value" ""
			(at 0 0 90)
			(layer "B.Fab")
			(effects
				(font
					(size 1.27 1.27)
				)
				(justify mirror)
			)
		)
		(duplicate_pad_numbers_are_jumpers no)
		(fp_line
			(start -0.7874 0.4064)
			(end 0.7874 0.4064)
			(stroke
				(width 0.1524)
				(type default)
			)
			(layer "B.SilkS")
		)
		(fp_line
			(start 0.7874 0.4064)
			(end 0.7874 -0.4064)
			(stroke
				(width 0.1524)
				(type default)
			)
			(layer "B.SilkS")
		)
		(fp_line
			(start -0.7874 -0.4064)
			(end -0.7874 0.4064)
			(stroke
				(width 0.1524)
				(type default)
			)
			(layer "B.SilkS")
		)
		(fp_line
			(start 0.7874 -0.4064)
			(end -0.7874 -0.4064)
			(stroke
				(width 0.1524)
				(type default)
			)
			(layer "B.SilkS")
		)
		(fp_line
			(start -0.67945 0.3048)
			(end -0.120396 0.3048)
			(stroke
				(width 0.1)
				(type default)
			)
			(layer "B.Fab")
		)
		(fp_line
			(start -0.120396 0.3048)
			(end -0.120396 0.2794)
			(stroke
				(width 0.1)
				(type default)
			)
			(layer "B.Fab")
		)
		(fp_line
			(start 0.12065 0.3048)
			(end 0.67945 0.3048)
			(stroke
				(width 0.1)
				(type default)
			)
			(layer "B.Fab")
		)
		(fp_line
			(start 0.67945 0.3048)
			(end 0.67945 -0.305054)
			(stroke
				(width 0.1)
				(type default)
			)
			(layer "B.Fab")
		)
		(fp_line
			(start -0.120396 0.2794)
			(end 0.12065 0.2794)
			(stroke
				(width 0.1)
				(type default)
			)
			(layer "B.Fab")
		)
		(fp_line
			(start 0.12065 0.2794)
			(end 0.12065 0.3048)
			(stroke
				(width 0.1)
				(type default)
			)
			(layer "B.Fab")
		)
		(fp_line
			(start -0.12065 -0.2794)
			(end -0.12065 -0.3048)
			(stroke
				(width 0.1)
				(type default)
			)
			(layer "B.Fab")
		)
		(fp_line
			(start 0.12065 -0.2794)
			(end -0.12065 -0.2794)
			(stroke
				(width 0.1)
				(type default)
			)
			(layer "B.Fab")
		)
		(fp_line
			(start -0.67945 -0.3048)
			(end -0.67945 0.3048)
			(stroke
				(width 0.1)
				(type default)
			)
			(layer "B.Fab")
		)
		(fp_line
			(start -0.12065 -0.3048)
			(end -0.67945 -0.3048)
			(stroke
				(width 0.1)
				(type default)
			)
			(layer "B.Fab")
		)
		(fp_line
			(start 0.12065 -0.305054)
			(end 0.12065 -0.2794)
			(stroke
				(width 0.1)
				(type default)
			)
			(layer "B.Fab")
		)
		(fp_line
			(start 0.67945 -0.305054)
			(end 0.12065 -0.305054)
			(stroke
				(width 0.1)
				(type default)
			)
			(layer "B.Fab")
		)
		(pad "1" smd circle
			(at 0.40005 0 90)
			(size 0 0)
			(layers "B.Cu" "B.Mask" "B.Paste")
			(net "PVNN_TERM_CPU0")
		)
		(pad "2" smd circle
			(at -0.40005 0 90)
			(size 0 0)
			(layers "B.Cu" "B.Mask" "B.Paste")
			(net "PU_CPU0_SOCKET_ID1")
		)
	)
	(footprint ""
		(layer "B.Cu")
		(at 12.666472 -184.625996)
		(property "Reference" "R2479"
			(at 0 0 0)
			(layer "B.SilkS")
			(hide yes)
			(effects
				(font
					(size 1.27 1.27)
				)
				(justify mirror)
			)
		)
		(property "Value" ""
			(at 0 0 0)
			(layer "B.Fab")
			(effects
				(font
					(size 1.27 1.27)
				)
				(justify mirror)
			)
		)
		(duplicate_pad_numbers_are_jumpers no)
		(fp_line
			(start -0.7874 -0.4064)
			(end -0.7874 0.4064)
			(stroke
				(width 0.1524)
				(type default)
			)
			(layer "B.SilkS")
		)
		(fp_line
			(start -0.7874 0.4064)
			(end 0.7874 0.4064)
			(stroke
				(width 0.1524)
				(type default)
			)
			(layer "B.SilkS")
		)
		(fp_line
			(start 0.7874 -0.4064)
			(end -0.7874 -0.4064)
			(stroke
				(width 0.1524)
				(type default)
			)
			(layer "B.SilkS")
		)
		(fp_line
			(start 0.7874 0.4064)
			(end 0.7874 -0.4064)
			(stroke
				(width 0.1524)
				(type default)
			)
			(layer "B.SilkS")
		)
		(fp_line
			(start -0.67945 -0.3048)
			(end -0.67945 0.3048)
			(stroke
				(width 0.1)
				(type default)
			)
			(layer "B.Fab")
		)
		(fp_line
			(start -0.67945 0.3048)
			(end -0.120396 0.3048)
			(stroke
				(width 0.1)
				(type default)
			)
			(layer "B.Fab")
		)
		(fp_line
			(start -0.12065 -0.3048)
			(end -0.67945 -0.3048)
			(stroke
				(width 0.1)
				(type default)
			)
			(layer "B.Fab")
		)
		(fp_line
			(start -0.12065 -0.2794)
			(end -0.12065 -0.3048)
			(stroke
				(width 0.1)
				(type default)
			)
			(layer "B.Fab")
		)
		(fp_line
			(start -0.120396 0.2794)
			(end 0.12065 0.2794)
			(stroke
				(width 0.1)
				(type default)
			)
			(layer "B.Fab")
		)
		(fp_line
			(start -0.120396 0.3048)
			(end -0.120396 0.2794)
			(stroke
				(width 0.1)
				(type default)
			)
			(layer "B.Fab")
		)
		(fp_line
			(start 0.12065 -0.305054)
			(end 0.12065 -0.2794)
			(stroke
				(width 0.1)
				(type default)
			)
			(layer "B.Fab")
		)
		(fp_line
			(start 0.12065 -0.2794)
			(end -0.12065 -0.2794)
			(stroke
				(width 0.1)
				(type default)
			)
			(layer "B.Fab")
		)
		(fp_line
			(start 0.12065 0.2794)
			(end 0.12065 0.3048)
			(stroke
				(width 0.1)
				(type default)
			)
			(layer "B.Fab")
		)
		(fp_line
			(start 0.12065 0.3048)
			(end 0.67945 0.3048)
			(stroke
				(width 0.1)
				(type default)
			)
			(layer "B.Fab")
		)
		(fp_line
			(start 0.67945 -0.305054)
			(end 0.12065 -0.305054)
			(stroke
				(width 0.1)
				(type default)
			)
			(layer "B.Fab")
		)
		(fp_line
			(start 0.67945 0.3048)
			(end 0.67945 -0.305054)
			(stroke
				(width 0.1)
				(type default)
			)
			(layer "B.Fab")
		)
		(pad "1" smd circle
			(at 0.40005 0 180)
			(size 0 0)
			(layers "B.Cu" "B.Mask" "B.Paste")
			(net "SMB_PEHPCPU1_LVC3_SCL_R0")
		)
		(pad "2" smd circle
			(at -0.40005 0 180)
			(size 0 0)
			(layers "B.Cu" "B.Mask" "B.Paste")
			(net "SMB_PEHPCPU1_LVC3_SCL")
		)
	)
)
